FILE_TYPE=LIBRARY_PARTS;
primitive 'H5AN4G6NAFR-TFC-GP';
  pin
    'VPP'<0>:
      PIN_NUMBER='(B1)';
      PINUSE='POWER';
      NO_LOAD_CHECK='Both';
      NO_IO_CHECK='Both';
      NO_ASSERT_CHECK='TRUE';
      NO_DIR_CHECK='TRUE';
      ALLOW_CONNECT='TRUE';
    'VDD'<0>:
      PIN_NUMBER='(B3)';
      PINUSE='POWER';
      NO_LOAD_CHECK='Both';
      NO_IO_CHECK='Both';
      NO_ASSERT_CHECK='TRUE';
      NO_DIR_CHECK='TRUE';
      ALLOW_CONNECT='TRUE';
    'VDD'<1>:
      PIN_NUMBER='(B9)';
      PINUSE='POWER';
      NO_LOAD_CHECK='Both';
      NO_IO_CHECK='Both';
      NO_ASSERT_CHECK='TRUE';
      NO_DIR_CHECK='TRUE';
      ALLOW_CONNECT='TRUE';
    'VDD'<2>:
      PIN_NUMBER='(D1)';
      PINUSE='POWER';
      NO_LOAD_CHECK='Both';
      NO_IO_CHECK='Both';
      NO_ASSERT_CHECK='TRUE';
      NO_DIR_CHECK='TRUE';
      ALLOW_CONNECT='TRUE';
    'VDD'<3>:
      PIN_NUMBER='(G7)';
      PINUSE='POWER';
      NO_LOAD_CHECK='Both';
      NO_IO_CHECK='Both';
      NO_ASSERT_CHECK='TRUE';
      NO_DIR_CHECK='TRUE';
      ALLOW_CONNECT='TRUE';
    'VDD'<4>:
      PIN_NUMBER='(J1)';
      PINUSE='POWER';
      NO_LOAD_CHECK='Both';
      NO_IO_CHECK='Both';
      NO_ASSERT_CHECK='TRUE';
      NO_DIR_CHECK='TRUE';
      ALLOW_CONNECT='TRUE';
    'VDD'<5>:
      PIN_NUMBER='(J9)';
      PINUSE='POWER';
      NO_LOAD_CHECK='Both';
      NO_IO_CHECK='Both';
      NO_ASSERT_CHECK='TRUE';
      NO_DIR_CHECK='TRUE';
      ALLOW_CONNECT='TRUE';
    'VDD'<6>:
      PIN_NUMBER='(L1)';
      PINUSE='POWER';
      NO_LOAD_CHECK='Both';
      NO_IO_CHECK='Both';
      NO_ASSERT_CHECK='TRUE';
      NO_DIR_CHECK='TRUE';
      ALLOW_CONNECT='TRUE';
    'VDD'<7>:
      PIN_NUMBER='(L9)';
      PINUSE='POWER';
      NO_LOAD_CHECK='Both';
      NO_IO_CHECK='Both';
      NO_ASSERT_CHECK='TRUE';
      NO_DIR_CHECK='TRUE';
      ALLOW_CONNECT='TRUE';
    'VDD'<8>:
      PIN_NUMBER='(R1)';
      PINUSE='POWER';
      NO_LOAD_CHECK='Both';
      NO_IO_CHECK='Both';
      NO_ASSERT_CHECK='TRUE';
      NO_DIR_CHECK='TRUE';
      ALLOW_CONNECT='TRUE';
    'VDD'<9>:
      PIN_NUMBER='(T9)';
      PINUSE='POWER';
      NO_LOAD_CHECK='Both';
      NO_IO_CHECK='Both';
      NO_ASSERT_CHECK='TRUE';
      NO_DIR_CHECK='TRUE';
      ALLOW_CONNECT='TRUE';
    'VDDQ'<0>:
      PIN_NUMBER='(A1)';
      PINUSE='POWER';
      NO_LOAD_CHECK='Both';
      NO_IO_CHECK='Both';
      NO_ASSERT_CHECK='TRUE';
      NO_DIR_CHECK='TRUE';
      ALLOW_CONNECT='TRUE';
    'VDDQ'<1>:
      PIN_NUMBER='(A9)';
      PINUSE='POWER';
      NO_LOAD_CHECK='Both';
      NO_IO_CHECK='Both';
      NO_ASSERT_CHECK='TRUE';
      NO_DIR_CHECK='TRUE';
      ALLOW_CONNECT='TRUE';
    'VDDQ'<2>:
      PIN_NUMBER='(C1)';
      PINUSE='POWER';
      NO_LOAD_CHECK='Both';
      NO_IO_CHECK='Both';
      NO_ASSERT_CHECK='TRUE';
      NO_DIR_CHECK='TRUE';
      ALLOW_CONNECT='TRUE';
    'VDDQ'<3>:
      PIN_NUMBER='(D9)';
      PINUSE='POWER';
      NO_LOAD_CHECK='Both';
      NO_IO_CHECK='Both';
      NO_ASSERT_CHECK='TRUE';
      NO_DIR_CHECK='TRUE';
      ALLOW_CONNECT='TRUE';
    'VDDQ'<4>:
      PIN_NUMBER='(F2)';
      PINUSE='POWER';
      NO_LOAD_CHECK='Both';
      NO_IO_CHECK='Both';
      NO_ASSERT_CHECK='TRUE';
      NO_DIR_CHECK='TRUE';
      ALLOW_CONNECT='TRUE';
    'VDDQ'<5>:
      PIN_NUMBER='(F8)';
      PINUSE='POWER';
      NO_LOAD_CHECK='Both';
      NO_IO_CHECK='Both';
      NO_ASSERT_CHECK='TRUE';
      NO_DIR_CHECK='TRUE';
      ALLOW_CONNECT='TRUE';
    'VDDQ'<6>:
      PIN_NUMBER='(G1)';
      PINUSE='POWER';
      NO_LOAD_CHECK='Both';
      NO_IO_CHECK='Both';
      NO_ASSERT_CHECK='TRUE';
      NO_DIR_CHECK='TRUE';
      ALLOW_CONNECT='TRUE';
    'VDDQ'<7>:
      PIN_NUMBER='(G9)';
      PINUSE='POWER';
      NO_LOAD_CHECK='Both';
      NO_IO_CHECK='Both';
      NO_ASSERT_CHECK='TRUE';
      NO_DIR_CHECK='TRUE';
      ALLOW_CONNECT='TRUE';
    'VDDQ'<8>:
      PIN_NUMBER='(J2)';
      PINUSE='POWER';
      NO_LOAD_CHECK='Both';
      NO_IO_CHECK='Both';
      NO_ASSERT_CHECK='TRUE';
      NO_DIR_CHECK='TRUE';
      ALLOW_CONNECT='TRUE';
    'VDDQ'<9>:
      PIN_NUMBER='(J8)';
      PINUSE='POWER';
      NO_LOAD_CHECK='Both';
      NO_IO_CHECK='Both';
      NO_ASSERT_CHECK='TRUE';
      NO_DIR_CHECK='TRUE';
      ALLOW_CONNECT='TRUE';
    'DQU4':
      PIN_NUMBER='(C2)';
      PIN_TYPE='ANALOG';
      NO_LOAD_CHECK='Both';
      NO_IO_CHECK='Both';
      NO_ASSERT_CHECK='TRUE';
      NO_DIR_CHECK='TRUE';
      ALLOW_CONNECT='TRUE';
    'DQU5':
      PIN_NUMBER='(C8)';
      PIN_TYPE='ANALOG';
      NO_LOAD_CHECK='Both';
      NO_IO_CHECK='Both';
      NO_ASSERT_CHECK='TRUE';
      NO_DIR_CHECK='TRUE';
      ALLOW_CONNECT='TRUE';
    'DQU6':
      PIN_NUMBER='(D3)';
      PIN_TYPE='ANALOG';
      NO_LOAD_CHECK='Both';
      NO_IO_CHECK='Both';
      NO_ASSERT_CHECK='TRUE';
      NO_DIR_CHECK='TRUE';
      ALLOW_CONNECT='TRUE';
    'DQU7':
      PIN_NUMBER='(D7)';
      PIN_TYPE='ANALOG';
      NO_LOAD_CHECK='Both';
      NO_IO_CHECK='Both';
      NO_ASSERT_CHECK='TRUE';
      NO_DIR_CHECK='TRUE';
      ALLOW_CONNECT='TRUE';
    'DQU0':
      PIN_NUMBER='(A3)';
      PIN_TYPE='ANALOG';
      NO_LOAD_CHECK='Both';
      NO_IO_CHECK='Both';
      NO_ASSERT_CHECK='TRUE';
      NO_DIR_CHECK='TRUE';
      ALLOW_CONNECT='TRUE';
    'DQU1':
      PIN_NUMBER='(B8)';
      PIN_TYPE='ANALOG';
      NO_LOAD_CHECK='Both';
      NO_IO_CHECK='Both';
      NO_ASSERT_CHECK='TRUE';
      NO_DIR_CHECK='TRUE';
      ALLOW_CONNECT='TRUE';
    'DQU2':
      PIN_NUMBER='(C3)';
      PIN_TYPE='ANALOG';
      NO_LOAD_CHECK='Both';
      NO_IO_CHECK='Both';
      NO_ASSERT_CHECK='TRUE';
      NO_DIR_CHECK='TRUE';
      ALLOW_CONNECT='TRUE';
    'DQU3':
      PIN_NUMBER='(C7)';
      PIN_TYPE='ANALOG';
      NO_LOAD_CHECK='Both';
      NO_IO_CHECK='Both';
      NO_ASSERT_CHECK='TRUE';
      NO_DIR_CHECK='TRUE';
      ALLOW_CONNECT='TRUE';
    'DQL1':
      PIN_NUMBER='(F7)';
      PIN_TYPE='ANALOG';
      NO_LOAD_CHECK='Both';
      NO_IO_CHECK='Both';
      NO_ASSERT_CHECK='TRUE';
      NO_DIR_CHECK='TRUE';
      ALLOW_CONNECT='TRUE';
    'DQL0':
      PIN_NUMBER='(G2)';
      PIN_TYPE='ANALOG';
      NO_LOAD_CHECK='Both';
      NO_IO_CHECK='Both';
      NO_ASSERT_CHECK='TRUE';
      NO_DIR_CHECK='TRUE';
      ALLOW_CONNECT='TRUE';
    'DQL4':
      PIN_NUMBER='(H2)';
      PIN_TYPE='ANALOG';
      NO_LOAD_CHECK='Both';
      NO_IO_CHECK='Both';
      NO_ASSERT_CHECK='TRUE';
      NO_DIR_CHECK='TRUE';
      ALLOW_CONNECT='TRUE';
    'DQL2':
      PIN_NUMBER='(H3)';
      PIN_TYPE='ANALOG';
      NO_LOAD_CHECK='Both';
      NO_IO_CHECK='Both';
      NO_ASSERT_CHECK='TRUE';
      NO_DIR_CHECK='TRUE';
      ALLOW_CONNECT='TRUE';
    'DQL3':
      PIN_NUMBER='(H7)';
      PIN_TYPE='ANALOG';
      NO_LOAD_CHECK='Both';
      NO_IO_CHECK='Both';
      NO_ASSERT_CHECK='TRUE';
      NO_DIR_CHECK='TRUE';
      ALLOW_CONNECT='TRUE';
    'DQL5':
      PIN_NUMBER='(H8)';
      PIN_TYPE='ANALOG';
      NO_LOAD_CHECK='Both';
      NO_IO_CHECK='Both';
      NO_ASSERT_CHECK='TRUE';
      NO_DIR_CHECK='TRUE';
      ALLOW_CONNECT='TRUE';
    'DQL6':
      PIN_NUMBER='(J3)';
      PIN_TYPE='ANALOG';
      NO_LOAD_CHECK='Both';
      NO_IO_CHECK='Both';
      NO_ASSERT_CHECK='TRUE';
      NO_DIR_CHECK='TRUE';
      ALLOW_CONNECT='TRUE';
    'DQL7':
      PIN_NUMBER='(J7)';
      PIN_TYPE='ANALOG';
      NO_LOAD_CHECK='Both';
      NO_IO_CHECK='Both';
      NO_ASSERT_CHECK='TRUE';
      NO_DIR_CHECK='TRUE';
      ALLOW_CONNECT='TRUE';
    'A0':
      PIN_NUMBER='(P3)';
      INPUT_LOAD='(-0.01,0.01)';
    'A1':
      PIN_NUMBER='(P7)';
      INPUT_LOAD='(-0.01,0.01)';
    'A2':
      PIN_NUMBER='(R3)';
      INPUT_LOAD='(-0.01,0.01)';
    'A3':
      PIN_NUMBER='(N7)';
      INPUT_LOAD='(-0.01,0.01)';
    'A4':
      PIN_NUMBER='(N3)';
      INPUT_LOAD='(-0.01,0.01)';
    'A5':
      PIN_NUMBER='(P8)';
      INPUT_LOAD='(-0.01,0.01)';
    'A6':
      PIN_NUMBER='(P2)';
      INPUT_LOAD='(-0.01,0.01)';
    'A7':
      PIN_NUMBER='(R8)';
      INPUT_LOAD='(-0.01,0.01)';
    'A8':
      PIN_NUMBER='(R2)';
      INPUT_LOAD='(-0.01,0.01)';
    'A9':
      PIN_NUMBER='(R7)';
      INPUT_LOAD='(-0.01,0.01)';
    'A10/AP':
      PIN_NUMBER='(M3)';
      INPUT_LOAD='(-0.01,0.01)';
    'A11':
      PIN_NUMBER='(T2)';
      INPUT_LOAD='(-0.01,0.01)';
    'A12/BC#':
      PIN_NUMBER='(M7)';
      INPUT_LOAD='(-0.01,0.01)';
    'A13':
      PIN_NUMBER='(T8)';
      INPUT_LOAD='(-0.01,0.01)';
    'WE#/A14':
      PIN_NUMBER='(L2)';
      INPUT_LOAD='(-0.01,0.01)';
    'CAS#/A15':
      PIN_NUMBER='(M8)';
      INPUT_LOAD='(-0.01,0.01)';
    'RAS#/A16':
      PIN_NUMBER='(L8)';
      INPUT_LOAD='(-0.01,0.01)';
    'VREFCA':
      PIN_NUMBER='(M1)';
      PIN_TYPE='ANALOG';
      NO_LOAD_CHECK='Both';
      NO_IO_CHECK='Both';
      NO_ASSERT_CHECK='TRUE';
      NO_DIR_CHECK='TRUE';
      ALLOW_CONNECT='TRUE';
    'ZQ':
      PIN_NUMBER='(F9)';
      PIN_TYPE='ANALOG';
      NO_LOAD_CHECK='Both';
      NO_IO_CHECK='Both';
      NO_ASSERT_CHECK='TRUE';
      NO_DIR_CHECK='TRUE';
      ALLOW_CONNECT='TRUE';
    'CKE':
      PIN_NUMBER='(K2)';
      INPUT_LOAD='(-0.01,0.01)';
    'ODT':
      PIN_NUMBER='(K3)';
      INPUT_LOAD='(-0.01,0.01)';
    'BG0':
      PIN_NUMBER='(M2)';
      INPUT_LOAD='(-0.01,0.01)';
    'TEN':
      PIN_NUMBER='(N9)';
      INPUT_LOAD='(-0.01,0.01)';
    'PAR':
      PIN_NUMBER='(T3)';
      INPUT_LOAD='(-0.01,0.01)';
    'NC#T7':
      PIN_NUMBER='(T7)';
      PIN_TYPE='ANALOG';
      NO_LOAD_CHECK='Both';
      NO_IO_CHECK='Both';
      NO_ASSERT_CHECK='TRUE';
      NO_DIR_CHECK='TRUE';
      ALLOW_CONNECT='TRUE';
    'CK_T':
      PIN_NUMBER='(K7)';
      INPUT_LOAD='(-0.01,0.01)';
    'CK_C':
      PIN_NUMBER='(K8)';
      INPUT_LOAD='(-0.01,0.01)';
    'VPP'<1>:
      PIN_NUMBER='(R9)';
      PINUSE='POWER';
      NO_LOAD_CHECK='Both';
      NO_IO_CHECK='Both';
      NO_ASSERT_CHECK='TRUE';
      NO_DIR_CHECK='TRUE';
      ALLOW_CONNECT='TRUE';
    'ACT#':
      PIN_NUMBER='(L3)';
      INPUT_LOAD='(-0.01,0.01)';
    'CS#':
      PIN_NUMBER='(L7)';
      INPUT_LOAD='(-0.01,0.01)';
    'RESET#':
      PIN_NUMBER='(P1)';
      INPUT_LOAD='(-0.01,0.01)';
    'ALERT#':
      PIN_NUMBER='(P9)';
      OUTPUT_LOAD='(1.0,-1.0)';
    'VSS'<0>:
      PIN_NUMBER='(B2)';
      PINUSE='POWER';
      NO_LOAD_CHECK='Both';
      NO_IO_CHECK='Both';
      NO_ASSERT_CHECK='TRUE';
      NO_DIR_CHECK='TRUE';
      ALLOW_CONNECT='TRUE';
    'VSS'<1>:
      PIN_NUMBER='(E1)';
      PINUSE='POWER';
      NO_LOAD_CHECK='Both';
      NO_IO_CHECK='Both';
      NO_ASSERT_CHECK='TRUE';
      NO_DIR_CHECK='TRUE';
      ALLOW_CONNECT='TRUE';
    'VSS'<2>:
      PIN_NUMBER='(E9)';
      PINUSE='POWER';
      NO_LOAD_CHECK='Both';
      NO_IO_CHECK='Both';
      NO_ASSERT_CHECK='TRUE';
      NO_DIR_CHECK='TRUE';
      ALLOW_CONNECT='TRUE';
    'VSS'<3>:
      PIN_NUMBER='(G8)';
      PINUSE='POWER';
      NO_LOAD_CHECK='Both';
      NO_IO_CHECK='Both';
      NO_ASSERT_CHECK='TRUE';
      NO_DIR_CHECK='TRUE';
      ALLOW_CONNECT='TRUE';
    'VSS'<4>:
      PIN_NUMBER='(K1)';
      PINUSE='POWER';
      NO_LOAD_CHECK='Both';
      NO_IO_CHECK='Both';
      NO_ASSERT_CHECK='TRUE';
      NO_DIR_CHECK='TRUE';
      ALLOW_CONNECT='TRUE';
    'VSS'<5>:
      PIN_NUMBER='(K9)';
      PINUSE='POWER';
      NO_LOAD_CHECK='Both';
      NO_IO_CHECK='Both';
      NO_ASSERT_CHECK='TRUE';
      NO_DIR_CHECK='TRUE';
      ALLOW_CONNECT='TRUE';
    'VSS'<6>:
      PIN_NUMBER='(M9)';
      PINUSE='POWER';
      NO_LOAD_CHECK='Both';
      NO_IO_CHECK='Both';
      NO_ASSERT_CHECK='TRUE';
      NO_DIR_CHECK='TRUE';
      ALLOW_CONNECT='TRUE';
    'VSS'<7>:
      PIN_NUMBER='(N1)';
      PINUSE='POWER';
      NO_LOAD_CHECK='Both';
      NO_IO_CHECK='Both';
      NO_ASSERT_CHECK='TRUE';
      NO_DIR_CHECK='TRUE';
      ALLOW_CONNECT='TRUE';
    'VSS'<8>:
      PIN_NUMBER='(T1)';
      PINUSE='POWER';
      NO_LOAD_CHECK='Both';
      NO_IO_CHECK='Both';
      NO_ASSERT_CHECK='TRUE';
      NO_DIR_CHECK='TRUE';
      ALLOW_CONNECT='TRUE';
    'VSSQ'<0>:
      PIN_NUMBER='(A2)';
      PINUSE='POWER';
      NO_LOAD_CHECK='Both';
      NO_IO_CHECK='Both';
      NO_ASSERT_CHECK='TRUE';
      NO_DIR_CHECK='TRUE';
      ALLOW_CONNECT='TRUE';
    'VSSQ'<1>:
      PIN_NUMBER='(A8)';
      PINUSE='POWER';
      NO_LOAD_CHECK='Both';
      NO_IO_CHECK='Both';
      NO_ASSERT_CHECK='TRUE';
      NO_DIR_CHECK='TRUE';
      ALLOW_CONNECT='TRUE';
    'VSSQ'<2>:
      PIN_NUMBER='(C9)';
      PINUSE='POWER';
      NO_LOAD_CHECK='Both';
      NO_IO_CHECK='Both';
      NO_ASSERT_CHECK='TRUE';
      NO_DIR_CHECK='TRUE';
      ALLOW_CONNECT='TRUE';
    'VSSQ'<3>:
      PIN_NUMBER='(D2)';
      PINUSE='POWER';
      NO_LOAD_CHECK='Both';
      NO_IO_CHECK='Both';
      NO_ASSERT_CHECK='TRUE';
      NO_DIR_CHECK='TRUE';
      ALLOW_CONNECT='TRUE';
    'VSSQ'<4>:
      PIN_NUMBER='(D8)';
      PINUSE='POWER';
      NO_LOAD_CHECK='Both';
      NO_IO_CHECK='Both';
      NO_ASSERT_CHECK='TRUE';
      NO_DIR_CHECK='TRUE';
      ALLOW_CONNECT='TRUE';
    'VSSQ'<5>:
      PIN_NUMBER='(E3)';
      PINUSE='POWER';
      NO_LOAD_CHECK='Both';
      NO_IO_CHECK='Both';
      NO_ASSERT_CHECK='TRUE';
      NO_DIR_CHECK='TRUE';
      ALLOW_CONNECT='TRUE';
    'VSSQ'<6>:
      PIN_NUMBER='(E8)';
      PINUSE='POWER';
      NO_LOAD_CHECK='Both';
      NO_IO_CHECK='Both';
      NO_ASSERT_CHECK='TRUE';
      NO_DIR_CHECK='TRUE';
      ALLOW_CONNECT='TRUE';
    'VSSQ'<7>:
      PIN_NUMBER='(F1)';
      PINUSE='POWER';
      NO_LOAD_CHECK='Both';
      NO_IO_CHECK='Both';
      NO_ASSERT_CHECK='TRUE';
      NO_DIR_CHECK='TRUE';
      ALLOW_CONNECT='TRUE';
    'VSSQ'<8>:
      PIN_NUMBER='(H1)';
      PINUSE='POWER';
      NO_LOAD_CHECK='Both';
      NO_IO_CHECK='Both';
      NO_ASSERT_CHECK='TRUE';
      NO_DIR_CHECK='TRUE';
      ALLOW_CONNECT='TRUE';
    'VSSQ'<9>:
      PIN_NUMBER='(H9)';
      PINUSE='POWER';
      NO_LOAD_CHECK='Both';
      NO_IO_CHECK='Both';
      NO_ASSERT_CHECK='TRUE';
      NO_DIR_CHECK='TRUE';
      ALLOW_CONNECT='TRUE';
    'DQSU_C':
      PIN_NUMBER='(A7)';
      BIDIRECTIONAL='TRUE';
      INPUT_LOAD='(-0.01,0.01)';
      OUTPUT_LOAD='(1.0,-1.0)';
    'DQSU_T':
      PIN_NUMBER='(B7)';
      BIDIRECTIONAL='TRUE';
      INPUT_LOAD='(-0.01,0.01)';
      OUTPUT_LOAD='(1.0,-1.0)';
    'DQSL_C':
      PIN_NUMBER='(F3)';
      BIDIRECTIONAL='TRUE';
      INPUT_LOAD='(-0.01,0.01)';
      OUTPUT_LOAD='(1.0,-1.0)';
    'DQSL_T':
      PIN_NUMBER='(G3)';
      BIDIRECTIONAL='TRUE';
      INPUT_LOAD='(-0.01,0.01)';
      OUTPUT_LOAD='(1.0,-1.0)';
    'DMU#/DBIU#':
      PIN_NUMBER='(E2)';
      BIDIRECTIONAL='TRUE';
      INPUT_LOAD='(-0.01,0.01)';
      OUTPUT_LOAD='(1.0,-1.0)';
    'DML#/DBIL#':
      PIN_NUMBER='(E7)';
      BIDIRECTIONAL='TRUE';
      INPUT_LOAD='(-0.01,0.01)';
      OUTPUT_LOAD='(1.0,-1.0)';
    'BA0':
      PIN_NUMBER='(N2)';
      INPUT_LOAD='(-0.01,0.01)';
    'BA1':
      PIN_NUMBER='(N8)';
      INPUT_LOAD='(-0.01,0.01)';
  end_pin;
  body
    PART_NAME='H5AN4G6NAFR-TFC-GP';
    BODY_NAME='H5AN4G6NAFR-TFC-GP';
    PHYS_DES_PREFIX='U';
    CLASS='IC';
  end_body;
end_primitive;

END.
